# BASEBOARD_FAB2 (Tioga Pass) — schematic netlist excerpt (pin names and nets, part order shuffled) for the footprints in the layout excerpt that follows; sources: Cadence DE-HDL packaged netlist, KiCad conversion of Wiwynn_Tioga_Pass_MB.brd

R3T9  RES  10.0K 1% EMPTY  pkg 0402  page 153 : A = PU_BIOS_SPI_WP1_N ; B = GND
C2P7  CAP_A  0.1UF 16V 10% X7R  pkg 0402V  page 192 : A = P3V3_STBY ; B = GND
C2N24  CAP  10UF 6.3V 20% X6S  pkg 0603  page 130 : A = P3V3_STBY ; B = GND

(kicad_pcb
	(version 20260206)
	(generator "pcbnew")
	(generator_version "10.0")
	(general
		(thickness 1.6)
		(legacy_teardrops no)
	)
	(paper "A4")
	(title_block
		(title "Wiwynn_Tioga_Pass_MB.brd")
		(comment 1 "Tioga Pass / footprints 3721-3723 of 4770")
	)
	(layers
		(0 "F.Cu" signal "TOP")
		(4 "In1.Cu" signal "L2GND")
		(6 "In2.Cu" signal "L3")
		(8 "In3.Cu" signal "L4GND")
		(10 "In4.Cu" signal "L5")
		(12 "In5.Cu" signal "L6GND")
		(14 "In6.Cu" signal "L7VCC")
		(16 "In7.Cu" signal "L8VCC")
		(18 "In8.Cu" signal "L9GND")
		(20 "In9.Cu" signal "L10")
		(22 "In10.Cu" signal "L11GND")
		(24 "In11.Cu" signal "L12")
		(26 "In12.Cu" signal "L13GND")
		(2 "B.Cu" signal "BOTTOM")
		(9 "F.Adhes" user "F.Adhesive")
		(11 "B.Adhes" user "B.Adhesive")
		(13 "F.Paste" user "Package Geometry/Pastemask Top")
		(15 "B.Paste" user "Package Geometry/Pastemask Bottom")
		(5 "F.SilkS" user "Ref Des/Silkscreen Top")
		(7 "B.SilkS" user "Ref Des/Silkscreen Bottom")
		(1 "F.Mask" user "Board Geometry/Soldermask Top")
		(3 "B.Mask" user "Board Geometry/Soldermask Bottom")
		(17 "Dwgs.User" user "User.Drawings")
		(19 "Cmts.User" user "User.Comments")
		(21 "Eco1.User" user "User.Eco1")
		(23 "Eco2.User" user "User.Eco2")
		(25 "Edge.Cuts" user "Board Geometry/Outline")
		(27 "Margin" user)
		(31 "F.CrtYd" user "Package Geometry/Place Bound Top")
		(29 "B.CrtYd" user "Package Geometry/Place Bound Bottom")
		(35 "F.Fab" user "Ref Des/Assembly Top")
		(33 "B.Fab" user "Ref Des/Assembly Bottom")
	)
	(footprint ""
		(layer "B.Cu")
		(at 371.545358 -75.494388)
		(property "Reference" "C2P7"
			(at 0 0 0)
			(layer "B.SilkS")
			(hide yes)
			(effects
				(font
					(size 1.27 1.27)
				)
				(justify mirror)
			)
		)
		(property "Value" ""
			(at 0 0 0)
			(layer "B.Fab")
			(effects
				(font
					(size 1.27 1.27)
				)
				(justify mirror)
			)
		)
		(duplicate_pad_numbers_are_jumpers no)
		(fp_rect
			(start 0.2794 0.9144)
			(end -0.2794 -0.1143)
			(stroke
				(width 0)
				(type default)
			)
			(fill no)
			(layer "B.CrtYd")
		)
		(fp_line
			(start -0.2794 -0.1143)
			(end -0.2794 0.9144)
			(stroke
				(width 0.1)
				(type default)
			)
			(layer "B.Fab")
		)
		(fp_line
			(start -0.2794 0.9144)
			(end 0.2794 0.9144)
			(stroke
				(width 0.1)
				(type default)
			)
			(layer "B.Fab")
		)
		(fp_line
			(start 0.2794 -0.1143)
			(end -0.2794 -0.1143)
			(stroke
				(width 0.1)
				(type default)
			)
			(layer "B.Fab")
		)
		(fp_line
			(start 0.2794 0.9144)
			(end 0.2794 -0.1143)
			(stroke
				(width 0.1)
				(type default)
			)
			(layer "B.Fab")
		)
		(pad "1" smd custom
			(at 0 0 270)
			(size 0.10414 0.10414)
			(layers "B.Cu" "B.Mask" "B.Paste")
			(net "P3V3_STBY")
			(options
				(clearance outline)
				(anchor circle)
			)
			(primitives
				(gr_poly
					(pts
						(xy -0.20828 -0.08636) (xy -0.20828 0.08636) (xy -0.08636 0.20828) (xy 0.086614 0.20828) (xy 0.20828 0.086614)
						(xy 0.20828 -0.08636) (xy 0.08636 -0.20828) (xy -0.08636 -0.20828)
					)
					(width 0)
					(fill yes)
				)
			)
		)
		(pad "2" smd custom
			(at 0 0.8001 270)
			(size 0.10414 0.10414)
			(layers "B.Cu" "B.Mask" "B.Paste")
			(net "GND")
			(options
				(clearance outline)
				(anchor circle)
			)
			(primitives
				(gr_poly
					(pts
						(xy -0.20828 -0.08636) (xy -0.20828 0.08636) (xy -0.08636 0.20828) (xy 0.086614 0.20828) (xy 0.20828 0.086614)
						(xy 0.20828 -0.08636) (xy 0.08636 -0.20828) (xy -0.08636 -0.20828)
					)
					(width 0)
					(fill yes)
				)
			)
		)
		(zone
			(layer "B.Cu")
			(hatch none 0.5)
			(connect_pads
				(clearance 0)
			)
			(min_thickness 0.25)
			(keepout
				(tracks allowed)
				(vias not_allowed)
				(pads allowed)
				(copperpour not_allowed)
				(footprints allowed)
			)
			(placement
				(enabled no)
				(sheetname "")
			)
			(fill
				(thermal_gap 0.5)
				(thermal_bridge_width 0.5)
				(island_removal_mode 0)
			)
			(polygon
				(pts
					(xy 371.632988 -75.284838) (xy 371.632988 -74.903838) (xy 371.457728 -74.903838) (xy 371.457474 -75.284838)
				)
			)
		)
		(zone
			(layer "B.Cu")
			(hatch none 0.5)
			(connect_pads
				(clearance 0)
			)
			(min_thickness 0.25)
			(keepout
				(tracks not_allowed)
				(vias allowed)
				(pads allowed)
				(copperpour not_allowed)
				(footprints allowed)
			)
			(placement
				(enabled no)
				(sheetname "")
			)
			(fill
				(thermal_gap 0.5)
				(thermal_bridge_width 0.5)
				(island_removal_mode 0)
			)
			(polygon
				(pts
					(xy 371.632988 -75.284838) (xy 371.632988 -74.903838) (xy 371.457728 -74.903838) (xy 371.457474 -75.284838)
				)
			)
		)
	)
	(footprint ""
		(layer "B.Cu")
		(at 408.7622 -103.8098)
		(property "Reference" "C2N24"
			(at 0 0 0)
			(layer "B.SilkS")
			(hide yes)
			(effects
				(font
					(size 1.27 1.27)
				)
				(justify mirror)
			)
		)
		(property "Value" ""
			(at 0 0 0)
			(layer "B.Fab")
			(effects
				(font
					(size 1.27 1.27)
				)
				(justify mirror)
			)
		)
		(duplicate_pad_numbers_are_jumpers no)
		(fp_poly
			(pts
				(xy 0.4953 -0.2032) (xy -0.4953 -0.2032) (xy -0.4953 1.6002) (xy 0.4953 1.6002)
			)
			(stroke
				(width 0)
				(type default)
			)
			(fill no)
			(layer "B.CrtYd")
		)
		(fp_line
			(start -0.4953 -0.2032)
			(end -0.4953 1.6002)
			(stroke
				(width 0.1)
				(type default)
			)
			(layer "B.Fab")
		)
		(fp_line
			(start -0.4953 1.6002)
			(end 0.4953 1.6002)
			(stroke
				(width 0.1)
				(type default)
			)
			(layer "B.Fab")
		)
		(fp_line
			(start 0.4953 -0.2032)
			(end -0.4953 -0.2032)
			(stroke
				(width 0.1)
				(type default)
			)
			(layer "B.Fab")
		)
		(fp_line
			(start 0.4953 1.6002)
			(end 0.4953 -0.2032)
			(stroke
				(width 0.1)
				(type default)
			)
			(layer "B.Fab")
		)
		(pad "1" smd rect
			(at 0 0 180)
			(size 0.762 0.889)
			(layers "B.Cu" "B.Mask" "B.Paste")
			(net "P3V3_STBY")
		)
		(pad "2" smd rect
			(at 0 1.397 180)
			(size 0.762 0.889)
			(layers "B.Cu" "B.Mask" "B.Paste")
			(net "GND")
		)
		(zone
			(layer "B.Cu")
			(hatch none 0.5)
			(connect_pads
				(clearance 0)
			)
			(min_thickness 0.25)
			(keepout
				(tracks not_allowed)
				(vias allowed)
				(pads allowed)
				(copperpour not_allowed)
				(footprints allowed)
			)
			(placement
				(enabled no)
				(sheetname "")
			)
			(fill
				(thermal_gap 0.5)
				(thermal_bridge_width 0.5)
				(island_removal_mode 0)
			)
			(polygon
				(pts
					(xy 409.1432 -103.3653) (xy 408.3812 -103.3653) (xy 408.3812 -102.8573) (xy 409.1432 -102.8573)
				)
			)
		)
	)
	(footprint ""
		(layer "B.Cu")
		(at 386.969 -47.244 -90)
		(property "Reference" "R3T9"
			(at 0 0 90)
			(layer "B.SilkS")
			(hide yes)
			(effects
				(font
					(size 1.27 1.27)
				)
				(justify mirror)
			)
		)
		(property "Value" ""
			(at 0 0 90)
			(layer "B.Fab")
			(effects
				(font
					(size 1.27 1.27)
				)
				(justify mirror)
			)
		)
		(duplicate_pad_numbers_are_jumpers no)
		(fp_poly
			(pts
				(xy 0.2794 -0.1016) (xy -0.2794 -0.1016) (xy -0.2794 0.9906) (xy 0.2794 0.9906)
			)
			(stroke
				(width 0)
				(type default)
			)
			(fill no)
			(layer "B.CrtYd")
		)
		(fp_line
			(start -0.2794 0.9906)
			(end -0.2794 -0.1016)
			(stroke
				(width 0.1)
				(type default)
			)
			(layer "B.Fab")
		)
		(fp_line
			(start 0.2794 0.9906)
			(end -0.2794 0.9906)
			(stroke
				(width 0.1)
				(type default)
			)
			(layer "B.Fab")
		)
		(fp_line
			(start -0.2794 -0.1016)
			(end 0.2794 -0.1016)
			(stroke
				(width 0.1)
				(type default)
			)
			(layer "B.Fab")
		)
		(fp_line
			(start 0.2794 -0.1016)
			(end 0.2794 0.9906)
			(stroke
				(width 0.1)
				(type default)
			)
			(layer "B.Fab")
		)
		(pad "1" smd rect
			(at 0 0 90)
			(size 0.508 0.508)
			(layers "B.Cu" "B.Mask" "B.Paste")
			(net "PU_BIOS_SPI_WP1_N")
		)
		(pad "2" smd rect
			(at 0 0.889 90)
			(size 0.508 0.508)
			(layers "B.Cu" "B.Mask" "B.Paste")
			(net "GND")
		)
		(zone
			(layer "B.Cu")
			(hatch none 0.5)
			(connect_pads
				(clearance 0)
			)
			(min_thickness 0.25)
			(keepout
				(tracks not_allowed)
				(vias allowed)
				(pads allowed)
				(copperpour not_allowed)
				(footprints allowed)
			)
			(placement
				(enabled no)
				(sheetname "")
			)
			(fill
				(thermal_gap 0.5)
				(thermal_bridge_width 0.5)
				(island_removal_mode 0)
			)
			(polygon
				(pts
					(xy 386.334 -46.99) (xy 386.334 -47.498) (xy 386.715 -47.498) (xy 386.715 -46.99)
				)
			)
		)
		(zone
			(layer "B.Cu")
			(hatch none 0.5)
			(connect_pads
				(clearance 0)
			)
			(min_thickness 0.25)
			(keepout
				(tracks allowed)
				(vias not_allowed)
				(pads allowed)
				(copperpour not_allowed)
				(footprints allowed)
			)
			(placement
				(enabled no)
				(sheetname "")
			)
			(fill
				(thermal_gap 0.5)
				(thermal_bridge_width 0.5)
				(island_removal_mode 0)
			)
			(polygon
				(pts
					(xy 386.715 -46.99) (xy 386.715 -47.498) (xy 386.334 -47.498) (xy 386.334 -46.99)
				)
			)
		)
	)
)
